# S9S_MB_2U (Grand Teton) — schematic netlist excerpt (pin names and nets, part order shuffled) for the footprints in the layout excerpt that follows; sources: Cadence DE-HDL packaged netlist, KiCad conversion of 03242023_DA0F0TMBIJ0_F0T_Motherboard_J_brd_V01_OCP.brd

PC1272  Q_CAP  22UF 16V 20% X6S  pkg C0805  page 282 : A = SW_P12V_PVCCINFAON_CPU0_FLT ; B = GND
C2268  Q_CAP  1000PF 50V 5% EMPTY  pkg 0402  page 146 : A = GPU_3V3IO_RSVD5_FFU_ISO ; B = GND
D80  Q_LED  IC  pkg SMLF  page 254 : A = LED_PWRGD_PVCCD_HV_CPU1 ; C = LED_PWRGD_PVCCD_HV_CPU1_D

(kicad_pcb
	(version 20260206)
	(generator "pcbnew")
	(generator_version "10.0")
	(general
		(thickness 1.6)
		(legacy_teardrops no)
	)
	(paper "A4")
	(title_block
		(title "03242023_DA0F0TMBIJ0_F0T_Motherboard_J_brd_V01_OCP.brd")
		(comment 1 "Grand Teton / footprints 3962-3964 of 6105")
	)
	(layers
		(0 "F.Cu" signal "TOP")
		(4 "In1.Cu" signal "GND")
		(6 "In2.Cu" signal "IN1")
		(8 "In3.Cu" signal "GND1")
		(10 "In4.Cu" signal "IN2")
		(12 "In5.Cu" signal "GND2")
		(14 "In6.Cu" signal "IN3")
		(16 "In7.Cu" signal "GND3")
		(18 "In8.Cu" signal "VCC")
		(20 "In9.Cu" signal "VCC1")
		(22 "In10.Cu" signal "GND4")
		(24 "In11.Cu" signal "IN4")
		(26 "In12.Cu" signal "GND5")
		(28 "In13.Cu" signal "IN5")
		(30 "In14.Cu" signal "GND6")
		(32 "In15.Cu" signal "IN6")
		(34 "In16.Cu" signal "GND7")
		(2 "B.Cu" signal "BOTTOM")
		(9 "F.Adhes" user "F.Adhesive")
		(11 "B.Adhes" user "B.Adhesive")
		(13 "F.Paste" user "Package Geometry/Pastemask Top")
		(15 "B.Paste" user "Package Geometry/Pastemask Bottom")
		(5 "F.SilkS" user "Ref Des/Silkscreen Top")
		(7 "B.SilkS" user "Ref Des/Silkscreen Bottom")
		(1 "F.Mask" user "Board Geometry/Soldermask Top")
		(3 "B.Mask" user "Board Geometry/Soldermask Bottom")
		(17 "Dwgs.User" user "User.Drawings")
		(19 "Cmts.User" user "User.Comments")
		(21 "Eco1.User" user "User.Eco1")
		(23 "Eco2.User" user "User.Eco2")
		(25 "Edge.Cuts" user "Board Geometry/Outline")
		(27 "Margin" user)
		(31 "F.CrtYd" user "Package Geometry/Place Bound Top")
		(29 "B.CrtYd" user "Package Geometry/Place Bound Bottom")
		(35 "F.Fab" user "Ref Des/Assembly Top")
		(33 "B.Fab" user "Ref Des/Assembly Bottom")
	)
	(footprint ""
		(layer "F.Cu")
		(at 298.66082 -419.02761 -90)
		(property "Reference" "C2268"
			(at 0 0 270)
			(layer "F.SilkS")
			(hide yes)
			(effects
				(font
					(size 1.27 1.27)
				)
			)
		)
		(property "Value" ""
			(at 0 0 270)
			(layer "F.Fab")
			(effects
				(font
					(size 1.27 1.27)
				)
			)
		)
		(duplicate_pad_numbers_are_jumpers no)
		(fp_line
			(start -0.7874 0.4064)
			(end -0.7874 -0.4064)
			(stroke
				(width 0.1524)
				(type default)
			)
			(layer "F.SilkS")
		)
		(fp_line
			(start 0.7874 0.4064)
			(end -0.7874 0.4064)
			(stroke
				(width 0.1524)
				(type default)
			)
			(layer "F.SilkS")
		)
		(fp_line
			(start -0.7874 -0.4064)
			(end 0.7874 -0.4064)
			(stroke
				(width 0.1524)
				(type default)
			)
			(layer "F.SilkS")
		)
		(fp_line
			(start 0.7874 -0.4064)
			(end 0.7874 0.4064)
			(stroke
				(width 0.1524)
				(type default)
			)
			(layer "F.SilkS")
		)
		(fp_line
			(start -0.67945 0.3048)
			(end -0.67945 -0.305054)
			(stroke
				(width 0.1)
				(type default)
			)
			(layer "F.Fab")
		)
		(fp_line
			(start -0.12065 0.3048)
			(end -0.67945 0.3048)
			(stroke
				(width 0.1)
				(type default)
			)
			(layer "F.Fab")
		)
		(fp_line
			(start 0.120396 0.3048)
			(end 0.120396 0.2794)
			(stroke
				(width 0.1)
				(type default)
			)
			(layer "F.Fab")
		)
		(fp_line
			(start 0.67945 0.3048)
			(end 0.120396 0.3048)
			(stroke
				(width 0.1)
				(type default)
			)
			(layer "F.Fab")
		)
		(fp_line
			(start -0.12065 0.2794)
			(end -0.12065 0.3048)
			(stroke
				(width 0.1)
				(type default)
			)
			(layer "F.Fab")
		)
		(fp_line
			(start 0.120396 0.2794)
			(end -0.12065 0.2794)
			(stroke
				(width 0.1)
				(type default)
			)
			(layer "F.Fab")
		)
		(fp_line
			(start -0.12065 -0.2794)
			(end 0.12065 -0.2794)
			(stroke
				(width 0.1)
				(type default)
			)
			(layer "F.Fab")
		)
		(fp_line
			(start 0.12065 -0.2794)
			(end 0.12065 -0.3048)
			(stroke
				(width 0.1)
				(type default)
			)
			(layer "F.Fab")
		)
		(fp_line
			(start 0.12065 -0.3048)
			(end 0.67945 -0.3048)
			(stroke
				(width 0.1)
				(type default)
			)
			(layer "F.Fab")
		)
		(fp_line
			(start 0.67945 -0.3048)
			(end 0.67945 0.3048)
			(stroke
				(width 0.1)
				(type default)
			)
			(layer "F.Fab")
		)
		(fp_line
			(start -0.67945 -0.305054)
			(end -0.12065 -0.305054)
			(stroke
				(width 0.1)
				(type default)
			)
			(layer "F.Fab")
		)
		(fp_line
			(start -0.12065 -0.305054)
			(end -0.12065 -0.2794)
			(stroke
				(width 0.1)
				(type default)
			)
			(layer "F.Fab")
		)
		(pad "1" smd circle
			(at -0.40005 0 270)
			(size 0 0)
			(layers "F.Cu" "F.Mask" "F.Paste")
			(net "GPU_3V3IO_RSVD5_FFU_ISO")
		)
		(pad "2" smd circle
			(at 0.40005 0 270)
			(size 0 0)
			(layers "F.Cu" "F.Mask" "F.Paste")
			(net "GND")
		)
	)
	(footprint ""
		(layer "F.Cu")
		(at 80.795876 -79.078836)
		(property "Reference" "D80"
			(at -41.50741 34.331402 90)
			(unlocked yes)
			(layer "F.SilkS")
			(effects
				(font
					(size 0.635 0.4064)
					(thickness 0.1524)
				)
				(justify left)
			)
		)
		(property "Value" ""
			(at 0 0 0)
			(layer "F.Fab")
			(effects
				(font
					(size 1.27 1.27)
				)
			)
		)
		(duplicate_pad_numbers_are_jumpers no)
		(fp_line
			(start -0.90678 0.4826)
			(end -0.90678 -0.4699)
			(stroke
				(width 0.1524)
				(type default)
			)
			(layer "F.SilkS")
		)
		(fp_line
			(start -0.89408 -0.4826)
			(end 0.90678 -0.4826)
			(stroke
				(width 0.1524)
				(type default)
			)
			(layer "F.SilkS")
		)
		(fp_line
			(start -0.79248 -0.4826)
			(end 1.03378 -0.4826)
			(stroke
				(width 0.1524)
				(type default)
			)
			(layer "F.SilkS")
		)
		(fp_line
			(start -0.64008 -0.4826)
			(end 1.16078 -0.4826)
			(stroke
				(width 0.1524)
				(type default)
			)
			(layer "F.SilkS")
		)
		(fp_line
			(start 0.90678 -0.4826)
			(end 0.90678 0.4826)
			(stroke
				(width 0.1524)
				(type default)
			)
			(layer "F.SilkS")
		)
		(fp_line
			(start 0.90678 0.4826)
			(end -0.90678 0.4826)
			(stroke
				(width 0.1524)
				(type default)
			)
			(layer "F.SilkS")
		)
		(fp_line
			(start 1.03378 -0.4826)
			(end 1.03378 0.4826)
			(stroke
				(width 0.1524)
				(type default)
			)
			(layer "F.SilkS")
		)
		(fp_line
			(start 1.03378 0.4826)
			(end -0.79248 0.4826)
			(stroke
				(width 0.1524)
				(type default)
			)
			(layer "F.SilkS")
		)
		(fp_line
			(start 1.16078 -0.4826)
			(end 1.16078 0.4826)
			(stroke
				(width 0.1524)
				(type default)
			)
			(layer "F.SilkS")
		)
		(fp_line
			(start 1.16078 0.4826)
			(end -0.64008 0.4826)
			(stroke
				(width 0.1524)
				(type default)
			)
			(layer "F.SilkS")
		)
		(fp_line
			(start -0.499872 -0.249936)
			(end 0.499872 -0.249936)
			(stroke
				(width 0.1)
				(type default)
			)
			(layer "F.Fab")
		)
		(fp_line
			(start -0.499872 0.249936)
			(end -0.499872 -0.249936)
			(stroke
				(width 0.1)
				(type default)
			)
			(layer "F.Fab")
		)
		(fp_line
			(start 0.499872 -0.249936)
			(end 0.499872 0.249936)
			(stroke
				(width 0.1)
				(type default)
			)
			(layer "F.Fab")
		)
		(fp_line
			(start 0.499872 0.249936)
			(end -0.499872 0.249936)
			(stroke
				(width 0.1)
				(type default)
			)
			(layer "F.Fab")
		)
		(pad "A" smd rect
			(at -0.47498 0)
			(size 0.6096 0.7112)
			(layers "F.Cu" "F.Mask" "F.Paste")
			(net "LED_PWRGD_PVCCD_HV_CPU1")
		)
		(pad "C" smd rect
			(at 0.47498 0)
			(size 0.6096 0.7112)
			(layers "F.Cu" "F.Mask" "F.Paste")
			(net "LED_PWRGD_PVCCD_HV_CPU1_D")
		)
	)
	(footprint ""
		(layer "F.Cu")
		(at 429.183038 -181.53507 90)
		(property "Reference" "PC1272"
			(at 0 0 90)
			(layer "F.SilkS")
			(hide yes)
			(effects
				(font
					(size 1.27 1.27)
				)
			)
		)
		(property "Value" ""
			(at 0 0 90)
			(layer "F.Fab")
			(effects
				(font
					(size 1.27 1.27)
				)
			)
		)
		(duplicate_pad_numbers_are_jumpers no)
		(fp_line
			(start 1.524 -0.762)
			(end 1.524 0.762)
			(stroke
				(width 0.1524)
				(type default)
			)
			(layer "F.SilkS")
		)
		(fp_line
			(start -1.524 -0.762)
			(end 1.524 -0.762)
			(stroke
				(width 0.1524)
				(type default)
			)
			(layer "F.SilkS")
		)
		(fp_line
			(start 1.524 0.762)
			(end -1.524 0.762)
			(stroke
				(width 0.1524)
				(type default)
			)
			(layer "F.SilkS")
		)
		(fp_line
			(start -1.524 0.762)
			(end -1.524 -0.762)
			(stroke
				(width 0.1524)
				(type default)
			)
			(layer "F.SilkS")
		)
		(fp_line
			(start 1.1049 -0.724916)
			(end -1.1049 -0.724916)
			(stroke
				(width 0.1)
				(type default)
			)
			(layer "F.Fab")
		)
		(fp_line
			(start -1.1049 -0.724916)
			(end -1.1049 0.724916)
			(stroke
				(width 0.1)
				(type default)
			)
			(layer "F.Fab")
		)
		(fp_line
			(start 1.1049 0.724916)
			(end 1.1049 -0.724916)
			(stroke
				(width 0.1)
				(type default)
			)
			(layer "F.Fab")
		)
		(fp_line
			(start -1.1049 0.724916)
			(end 1.1049 0.724916)
			(stroke
				(width 0.1)
				(type default)
			)
			(layer "F.Fab")
		)
		(pad "1" smd rect
			(at -0.889 0 270)
			(size 1.016 1.27)
			(layers "F.Cu" "F.Mask" "F.Paste")
			(net "SW_P12V_PVCCINFAON_CPU0_FLT")
		)
		(pad "2" smd rect
			(at 0.889 0 270)
			(size 1.016 1.27)
			(layers "F.Cu" "F.Mask" "F.Paste")
			(net "GND")
		)
	)
)
